# S9S_MB_2U (Grand Teton) — schematic netlist excerpt (pin names and nets, part order shuffled) for the footprints in the layout excerpt that follows; sources: Cadence DE-HDL packaged netlist, KiCad conversion of 03242023_DA0F0TMBIJ0_F0T_Motherboard_J_brd_V01_OCP.brd

R309  Q_RES  0 5% CHIP  pkg 0402LF  page 284 : A = FM_PVCCIN_CPU1_EN ; B = PVCCIN_CPU1_EN_R
C3267  Q_CAP  1000PF 50V 5% X7R  pkg 0402  page 266 : A = PVCCIN_CPU0_EN_R ; B = GND
C36  Q_CAP  10UF 16V 10% X6S  pkg C0805  page 93 : A = P12V_S3_AUX_CPU0_NVDIMM ; B = GND

(kicad_pcb
	(version 20260206)
	(generator "pcbnew")
	(generator_version "10.0")
	(general
		(thickness 1.6)
		(legacy_teardrops no)
	)
	(paper "A4")
	(title_block
		(title "03242023_DA0F0TMBIJ0_F0T_Motherboard_J_brd_V01_OCP.brd")
		(comment 1 "Grand Teton / footprints 4461-4463 of 6105")
	)
	(layers
		(0 "F.Cu" signal "TOP")
		(4 "In1.Cu" signal "GND")
		(6 "In2.Cu" signal "IN1")
		(8 "In3.Cu" signal "GND1")
		(10 "In4.Cu" signal "IN2")
		(12 "In5.Cu" signal "GND2")
		(14 "In6.Cu" signal "IN3")
		(16 "In7.Cu" signal "GND3")
		(18 "In8.Cu" signal "VCC")
		(20 "In9.Cu" signal "VCC1")
		(22 "In10.Cu" signal "GND4")
		(24 "In11.Cu" signal "IN4")
		(26 "In12.Cu" signal "GND5")
		(28 "In13.Cu" signal "IN5")
		(30 "In14.Cu" signal "GND6")
		(32 "In15.Cu" signal "IN6")
		(34 "In16.Cu" signal "GND7")
		(2 "B.Cu" signal "BOTTOM")
		(9 "F.Adhes" user "F.Adhesive")
		(11 "B.Adhes" user "B.Adhesive")
		(13 "F.Paste" user "Package Geometry/Pastemask Top")
		(15 "B.Paste" user "Package Geometry/Pastemask Bottom")
		(5 "F.SilkS" user "Ref Des/Silkscreen Top")
		(7 "B.SilkS" user "Ref Des/Silkscreen Bottom")
		(1 "F.Mask" user "Board Geometry/Soldermask Top")
		(3 "B.Mask" user "Board Geometry/Soldermask Bottom")
		(17 "Dwgs.User" user "User.Drawings")
		(19 "Cmts.User" user "User.Comments")
		(21 "Eco1.User" user "User.Eco1")
		(23 "Eco2.User" user "User.Eco2")
		(25 "Edge.Cuts" user "Board Geometry/Outline")
		(27 "Margin" user)
		(31 "F.CrtYd" user "Package Geometry/Place Bound Top")
		(29 "B.CrtYd" user "Package Geometry/Place Bound Bottom")
		(35 "F.Fab" user "Ref Des/Assembly Top")
		(33 "B.Fab" user "Ref Des/Assembly Bottom")
	)
	(footprint ""
		(layer "B.Cu")
		(at 354.221288 -359.47985 180)
		(property "Reference" "C3267"
			(at 0 0 0)
			(layer "B.SilkS")
			(hide yes)
			(effects
				(font
					(size 1.27 1.27)
				)
				(justify mirror)
			)
		)
		(property "Value" ""
			(at 0 0 0)
			(layer "B.Fab")
			(effects
				(font
					(size 1.27 1.27)
				)
				(justify mirror)
			)
		)
		(duplicate_pad_numbers_are_jumpers no)
		(fp_line
			(start 0.7874 0.4064)
			(end 0.7874 -0.4064)
			(stroke
				(width 0.1524)
				(type default)
			)
			(layer "B.SilkS")
		)
		(fp_line
			(start 0.7874 -0.4064)
			(end -0.7874 -0.4064)
			(stroke
				(width 0.1524)
				(type default)
			)
			(layer "B.SilkS")
		)
		(fp_line
			(start -0.7874 0.4064)
			(end 0.7874 0.4064)
			(stroke
				(width 0.1524)
				(type default)
			)
			(layer "B.SilkS")
		)
		(fp_line
			(start -0.7874 -0.4064)
			(end -0.7874 0.4064)
			(stroke
				(width 0.1524)
				(type default)
			)
			(layer "B.SilkS")
		)
		(fp_line
			(start 0.67945 0.3048)
			(end 0.67945 -0.305054)
			(stroke
				(width 0.1)
				(type default)
			)
			(layer "B.Fab")
		)
		(fp_line
			(start 0.67945 -0.305054)
			(end 0.12065 -0.305054)
			(stroke
				(width 0.1)
				(type default)
			)
			(layer "B.Fab")
		)
		(fp_line
			(start 0.12065 0.3048)
			(end 0.67945 0.3048)
			(stroke
				(width 0.1)
				(type default)
			)
			(layer "B.Fab")
		)
		(fp_line
			(start 0.12065 0.2794)
			(end 0.12065 0.3048)
			(stroke
				(width 0.1)
				(type default)
			)
			(layer "B.Fab")
		)
		(fp_line
			(start 0.12065 -0.2794)
			(end -0.12065 -0.2794)
			(stroke
				(width 0.1)
				(type default)
			)
			(layer "B.Fab")
		)
		(fp_line
			(start 0.12065 -0.305054)
			(end 0.12065 -0.2794)
			(stroke
				(width 0.1)
				(type default)
			)
			(layer "B.Fab")
		)
		(fp_line
			(start -0.120396 0.3048)
			(end -0.120396 0.2794)
			(stroke
				(width 0.1)
				(type default)
			)
			(layer "B.Fab")
		)
		(fp_line
			(start -0.120396 0.2794)
			(end 0.12065 0.2794)
			(stroke
				(width 0.1)
				(type default)
			)
			(layer "B.Fab")
		)
		(fp_line
			(start -0.12065 -0.2794)
			(end -0.12065 -0.3048)
			(stroke
				(width 0.1)
				(type default)
			)
			(layer "B.Fab")
		)
		(fp_line
			(start -0.12065 -0.3048)
			(end -0.67945 -0.3048)
			(stroke
				(width 0.1)
				(type default)
			)
			(layer "B.Fab")
		)
		(fp_line
			(start -0.67945 0.3048)
			(end -0.120396 0.3048)
			(stroke
				(width 0.1)
				(type default)
			)
			(layer "B.Fab")
		)
		(fp_line
			(start -0.67945 -0.3048)
			(end -0.67945 0.3048)
			(stroke
				(width 0.1)
				(type default)
			)
			(layer "B.Fab")
		)
		(pad "1" smd circle
			(at 0.40005 0)
			(size 0 0)
			(layers "B.Cu" "B.Mask" "B.Paste")
			(net "PVCCIN_CPU0_EN_R")
		)
		(pad "2" smd circle
			(at -0.40005 0)
			(size 0 0)
			(layers "B.Cu" "B.Mask" "B.Paste")
			(net "GND")
		)
	)
	(footprint ""
		(layer "B.Cu")
		(at 105.696258 -358.05491 -90)
		(property "Reference" "R309"
			(at 0 0 90)
			(layer "B.SilkS")
			(hide yes)
			(effects
				(font
					(size 1.27 1.27)
				)
				(justify mirror)
			)
		)
		(property "Value" ""
			(at 0 0 90)
			(layer "B.Fab")
			(effects
				(font
					(size 1.27 1.27)
				)
				(justify mirror)
			)
		)
		(duplicate_pad_numbers_are_jumpers no)
		(fp_line
			(start -0.7874 0.4064)
			(end 0.7874 0.4064)
			(stroke
				(width 0.1524)
				(type default)
			)
			(layer "B.SilkS")
		)
		(fp_line
			(start 0.7874 0.4064)
			(end 0.7874 -0.4064)
			(stroke
				(width 0.1524)
				(type default)
			)
			(layer "B.SilkS")
		)
		(fp_line
			(start -0.7874 -0.4064)
			(end -0.7874 0.4064)
			(stroke
				(width 0.1524)
				(type default)
			)
			(layer "B.SilkS")
		)
		(fp_line
			(start 0.7874 -0.4064)
			(end -0.7874 -0.4064)
			(stroke
				(width 0.1524)
				(type default)
			)
			(layer "B.SilkS")
		)
		(fp_line
			(start -0.67945 0.3048)
			(end -0.120396 0.3048)
			(stroke
				(width 0.1)
				(type default)
			)
			(layer "B.Fab")
		)
		(fp_line
			(start -0.120396 0.3048)
			(end -0.120396 0.2794)
			(stroke
				(width 0.1)
				(type default)
			)
			(layer "B.Fab")
		)
		(fp_line
			(start 0.12065 0.3048)
			(end 0.67945 0.3048)
			(stroke
				(width 0.1)
				(type default)
			)
			(layer "B.Fab")
		)
		(fp_line
			(start 0.67945 0.3048)
			(end 0.67945 -0.305054)
			(stroke
				(width 0.1)
				(type default)
			)
			(layer "B.Fab")
		)
		(fp_line
			(start -0.120396 0.2794)
			(end 0.12065 0.2794)
			(stroke
				(width 0.1)
				(type default)
			)
			(layer "B.Fab")
		)
		(fp_line
			(start 0.12065 0.2794)
			(end 0.12065 0.3048)
			(stroke
				(width 0.1)
				(type default)
			)
			(layer "B.Fab")
		)
		(fp_line
			(start -0.12065 -0.2794)
			(end -0.12065 -0.3048)
			(stroke
				(width 0.1)
				(type default)
			)
			(layer "B.Fab")
		)
		(fp_line
			(start 0.12065 -0.2794)
			(end -0.12065 -0.2794)
			(stroke
				(width 0.1)
				(type default)
			)
			(layer "B.Fab")
		)
		(fp_line
			(start -0.67945 -0.3048)
			(end -0.67945 0.3048)
			(stroke
				(width 0.1)
				(type default)
			)
			(layer "B.Fab")
		)
		(fp_line
			(start -0.12065 -0.3048)
			(end -0.67945 -0.3048)
			(stroke
				(width 0.1)
				(type default)
			)
			(layer "B.Fab")
		)
		(fp_line
			(start 0.12065 -0.305054)
			(end 0.12065 -0.2794)
			(stroke
				(width 0.1)
				(type default)
			)
			(layer "B.Fab")
		)
		(fp_line
			(start 0.67945 -0.305054)
			(end 0.12065 -0.305054)
			(stroke
				(width 0.1)
				(type default)
			)
			(layer "B.Fab")
		)
		(pad "1" smd circle
			(at 0.40005 0 90)
			(size 0 0)
			(layers "B.Cu" "B.Mask" "B.Paste")
			(net "FM_PVCCIN_CPU1_EN")
		)
		(pad "2" smd circle
			(at -0.40005 0 90)
			(size 0 0)
			(layers "B.Cu" "B.Mask" "B.Paste")
			(net "PVCCIN_CPU1_EN_R")
		)
	)
	(footprint ""
		(layer "B.Cu")
		(at 421.853614 -321.549776 -90)
		(property "Reference" "C36"
			(at 0 0 90)
			(layer "B.SilkS")
			(hide yes)
			(effects
				(font
					(size 1.27 1.27)
				)
				(justify mirror)
			)
		)
		(property "Value" ""
			(at 0 0 90)
			(layer "B.Fab")
			(effects
				(font
					(size 1.27 1.27)
				)
				(justify mirror)
			)
		)
		(duplicate_pad_numbers_are_jumpers no)
		(fp_line
			(start -1.524 0.762)
			(end 1.524 0.762)
			(stroke
				(width 0.1524)
				(type default)
			)
			(layer "B.SilkS")
		)
		(fp_line
			(start 1.524 0.762)
			(end 1.524 -0.762)
			(stroke
				(width 0.1524)
				(type default)
			)
			(layer "B.SilkS")
		)
		(fp_line
			(start -1.524 -0.762)
			(end -1.524 0.762)
			(stroke
				(width 0.1524)
				(type default)
			)
			(layer "B.SilkS")
		)
		(fp_line
			(start 1.524 -0.762)
			(end -1.524 -0.762)
			(stroke
				(width 0.1524)
				(type default)
			)
			(layer "B.SilkS")
		)
		(fp_line
			(start -1.1049 0.724916)
			(end -1.1049 -0.724916)
			(stroke
				(width 0.1)
				(type default)
			)
			(layer "B.Fab")
		)
		(fp_line
			(start 1.1049 0.724916)
			(end -1.1049 0.724916)
			(stroke
				(width 0.1)
				(type default)
			)
			(layer "B.Fab")
		)
		(fp_line
			(start -1.1049 -0.724916)
			(end 1.1049 -0.724916)
			(stroke
				(width 0.1)
				(type default)
			)
			(layer "B.Fab")
		)
		(fp_line
			(start 1.1049 -0.724916)
			(end 1.1049 0.724916)
			(stroke
				(width 0.1)
				(type default)
			)
			(layer "B.Fab")
		)
		(pad "1" smd rect
			(at 0.889 0 270)
			(size 1.016 1.27)
			(layers "B.Cu" "B.Mask" "B.Paste")
			(net "P12V_S3_AUX_CPU0_NVDIMM")
		)
		(pad "2" smd rect
			(at -0.889 0 270)
			(size 1.016 1.27)
			(layers "B.Cu" "B.Mask" "B.Paste")
			(net "GND")
		)
	)
)
